M48
INCH,TZ
T01C.01
T02C.02
T03C.023
T04C.026
T05C.028
T06C.04
T07C.086
T08C.165
;EXTENTS: -104.024 -105.698 109.976 105.302 
;LEADER: 12 
;HEADER: 
;CODE  : ASCII 
;FILE  : 16368-sb.rou for board 16368-sb.brd
%
G90
F1
M16
T03
M16
G00X55567Y46949
G40
M15
G01X57267
M16
G40
M30
